#ISCELL
  mstr_misc dns *
  *
#ISCELL
  pure_quanta quanta_title_block_c *
  *
#CELL
  pure_quanta q_res *
  page156_i100
#CELL
  pure_quanta q_res *
  page156_i101
#ISCELL
  pure_quanta_power universal_power *
  page156_i102
#ISCELL
  pure_quanta_power universal_gnd *
  page156_i103
#CELL
  pure_quanta mosfet_dual_6p *
  page156_i104
#ISCELL
  pure_quanta_power universal_gnd *
  page156_i105
#ISCELL
  pure_quanta_power universal_gnd *
  page156_i106
#CELL
  pure_quanta q_cap *
  page156_i107
#CELL
  pure_quanta q_cap *
  page156_i108
#ISCELL
  standard offpage *
  page156_i109
#ISCELL
  pure_quanta_power universal_gnd *
  page156_i110
#ISCELL
  pure_quanta_power universal_gnd *
  page156_i112
#CELL
  pure_quanta q_cap *
  page156_i113
#ISCELL
  standard offpage *
  page156_i114
#ISCELL
  standard offpage *
  page156_i115
#CELL
  pure_quanta q_res *
  page156_i116
#ISCELL
  pure_quanta_power universal_gnd *
  page156_i117
#CELL
  pure_quanta q_cap *
  page156_i118
#ISCELL
  standard offpage *
  page156_i119
#CELL
  pure_quanta q_res *
  page156_i120
#ISCELL
  pure_quanta_power universal_power *
  page156_i121
#CELL
  pure_quanta q_res *
  page156_i122
#ISCELL
  pure_quanta_power universal_gnd *
  page156_i123
#ISCELL
  pure_quanta_power universal_gnd *
  page156_i124
#CELL
  pure_quanta q_cap *
  page156_i125
#CELL
  pure_quanta q_cap *
  page156_i126
#ISCELL
  pure_quanta_power universal_gnd *
  page156_i127
#CELL
  pure_quanta conn3_210hp1030br1 *
  page156_i128
#CELL
  pure_quanta q_res *
  page156_i129
#CELL
  pure_quanta ncp698sq15t1g *
  page156_i130
#CELL
  pure_quanta q_res *
  page156_i131
#ISCELL
  pure_quanta_power gnd *
  page156_i85
#CELL
  pure_quanta conn2_aaabat029y19 *
  page156_i86
#ISCELL
  pure_quanta_power universal_power *
  page156_i87
#ISCELL
  standard offpage *
  page156_i88
#ISCELL
  standard offpage *
  page156_i89
#ISCELL
  pure_quanta_power universal_gnd *
  page156_i90
#CELL
  pure_quanta tps71715dckr *
  page156_i91
#ISCELL
  standard offpage *
  page156_i92
#ISCELL
  pure_quanta_power universal_gnd *
  page156_i93
#CELL
  pure_quanta q_res *
  page156_i94
#CELL
  pure_quanta q_cap *
  page156_i95
#CELL
  pure_quanta q_res *
  page156_i97
#ISCELL
  standard offpage *
  page156_i98
#CELL
  pure_quanta schottky_dual_12a_3c *
  page156_i99
